G04 ================== begin FILE IDENTIFICATION RECORD ==================*
G04 Layout Name:  12432-1.brd*
G04 Film Name:    BSMD*
G04 File Format:  Gerber RS274X*
G04 File Origin:  Cadence Allegro 16.2-S037*
G04 Origin Date:  Wed Oct 17 10:59:41 2012*
G04 *
G04 Layer:  VIA CLASS/PASTEMASK_BOTTOM*
G04 Layer:  PIN/PASTEMASK_BOTTOM*
G04 Layer:  PACKAGE GEOMETRY/PASTEMASK_BOTTOM*
G04 Layer:  DRAWING FORMAT/LAYER_PCB_STORY*
G04 Layer:  DRAWING FORMAT/LAYER_PAST_B*
G04 Layer:  BOARD GEOMETRY/PANEL_OUTLINE*
G04 *
G04 Offset:    (0.00 0.00)*
G04 Mirror:    No*
G04 Mode:      Positive*
G04 Rotation:  0*
G04 FullContactRelief:  No*
G04 UndefLineWidth:     6.00*
G04 ================== end FILE IDENTIFICATION RECORD ====================*
%FSLAX35Y35*MOIN*%
%IR0*IPPOS*OFA0.00000B0.00000*MIA0B0*SFA1.00000B1.00000*%
%ADD13R,.23X.032*%
%ADD12R,.142X.028*%
%ADD10R,.05X.05*%
%ADD11C,.086*%
%ADD14C,.01*%
%ADD15C,.02*%
%ADD16C,.006*%
G75*
%LPD*%
G75*
G36*
G01X1017308Y1433722D02*
Y1451397D01*
X991708D01*
Y1433722D01*
X1017308D01*
G37*
G36*
G01Y1453247D02*
Y1470922D01*
X991708D01*
Y1453247D01*
X1017308D01*
G37*
G36*
G01Y1473722D02*
Y1491397D01*
X991708D01*
Y1473722D01*
X1017308D01*
G37*
G36*
G01Y1493247D02*
Y1510922D01*
X991708D01*
Y1493247D01*
X1017308D01*
G37*
G36*
G01Y1513722D02*
Y1531397D01*
X991708D01*
Y1513722D01*
X1017308D01*
G37*
G36*
G01Y1553722D02*
Y1571397D01*
X991708D01*
Y1553722D01*
X1017308D01*
G37*
G36*
G01Y1533247D02*
Y1550922D01*
X991708D01*
Y1533247D01*
X1017308D01*
G37*
G36*
G01Y1573247D02*
Y1590922D01*
X991708D01*
Y1573247D01*
X1017308D01*
G37*
G36*
G01X1017307Y1593722D02*
Y1610922D01*
X991708D01*
Y1593722D01*
X1017307D01*
G37*
G54D10*
X-38666Y47522D03*
X-37468Y1947630D03*
X21499Y17050D03*
X1010999Y18550D03*
X1008999Y1968550D03*
X1073242Y50048D03*
G54D11*
X-38436Y23633D03*
X-36811Y1104775D03*
X-35919Y1969497D03*
X1072493Y21507D03*
X1075940Y1769358D03*
G54D12*
X12569Y391726D03*
Y387789D03*
Y383852D03*
Y379915D03*
Y375978D03*
Y372041D03*
Y411411D03*
Y407474D03*
Y403537D03*
Y399600D03*
Y395663D03*
Y431098D03*
Y427161D03*
Y423223D03*
Y454720D03*
Y450783D03*
Y446846D03*
Y442909D03*
Y438972D03*
Y435035D03*
Y474405D03*
Y470468D03*
Y466531D03*
Y462594D03*
Y458657D03*
Y494090D03*
Y490153D03*
Y486216D03*
Y482279D03*
Y478342D03*
Y517712D03*
Y513775D03*
Y509838D03*
Y505901D03*
Y501964D03*
Y498027D03*
Y537397D03*
Y533460D03*
Y529523D03*
Y525586D03*
Y521649D03*
Y561019D03*
Y557082D03*
Y553145D03*
Y549208D03*
Y545271D03*
Y541334D03*
Y580704D03*
Y576767D03*
Y572830D03*
Y568893D03*
Y564956D03*
Y600389D03*
Y596452D03*
Y592515D03*
Y584641D03*
Y588578D03*
Y624011D03*
Y620074D03*
Y616137D03*
Y612200D03*
Y604326D03*
Y608263D03*
Y643696D03*
Y639759D03*
Y635822D03*
Y631885D03*
Y627948D03*
Y663381D03*
Y659444D03*
Y655507D03*
Y651570D03*
Y647633D03*
Y687003D03*
Y683066D03*
Y679129D03*
Y675192D03*
Y671255D03*
Y667318D03*
Y698814D03*
Y694877D03*
Y690940D03*
X12560Y793325D03*
Y789388D03*
Y785451D03*
Y781514D03*
Y813010D03*
Y809073D03*
Y805136D03*
Y801199D03*
Y797262D03*
Y820884D03*
Y816947D03*
Y832696D03*
Y856318D03*
Y852381D03*
Y848444D03*
Y844507D03*
Y840570D03*
Y836633D03*
X12569Y1364167D03*
Y1360230D03*
Y1356293D03*
Y1383852D03*
Y1379915D03*
Y1375978D03*
Y1372041D03*
Y1368104D03*
Y1395663D03*
Y1391726D03*
Y1387789D03*
Y1427161D03*
Y1423224D03*
Y1419287D03*
Y1415350D03*
Y1411413D03*
Y1407475D03*
Y1446846D03*
Y1442909D03*
Y1438972D03*
Y1435035D03*
Y1431098D03*
Y1470468D03*
Y1466531D03*
Y1462594D03*
Y1458657D03*
Y1454720D03*
Y1450783D03*
Y1490153D03*
Y1486216D03*
Y1482279D03*
Y1478342D03*
Y1474405D03*
Y1509838D03*
Y1505901D03*
Y1501964D03*
Y1498027D03*
Y1494090D03*
Y1533460D03*
Y1529523D03*
Y1525586D03*
Y1521649D03*
Y1517712D03*
Y1513775D03*
Y1553145D03*
Y1549208D03*
Y1545271D03*
Y1541334D03*
Y1537397D03*
Y1568893D03*
Y1572830D03*
Y1564956D03*
Y1561019D03*
Y1557082D03*
Y1596452D03*
Y1588578D03*
Y1592515D03*
Y1584641D03*
Y1580704D03*
Y1576767D03*
Y1616137D03*
Y1612200D03*
Y1608263D03*
Y1604326D03*
Y1600389D03*
Y1639759D03*
Y1635822D03*
Y1631885D03*
Y1627948D03*
Y1624011D03*
Y1620074D03*
Y1659444D03*
Y1655507D03*
Y1651570D03*
Y1647633D03*
Y1643696D03*
Y1679129D03*
Y1675192D03*
Y1671255D03*
Y1667318D03*
Y1663381D03*
Y1683066D03*
X12560Y1765766D03*
Y1785451D03*
Y1781514D03*
Y1777577D03*
Y1773640D03*
Y1769703D03*
Y1805136D03*
Y1801199D03*
Y1797262D03*
Y1793325D03*
Y1789388D03*
Y1828759D03*
Y1824822D03*
Y1820885D03*
Y1816948D03*
Y1840570D03*
Y1836633D03*
Y1832696D03*
G54D13*
X1005807Y1636102D03*
Y1631102D03*
Y1626102D03*
Y1621102D03*
Y1661102D03*
Y1656102D03*
Y1651102D03*
Y1646102D03*
Y1641102D03*
Y1676102D03*
Y1671102D03*
Y1666102D03*
G54D14*
G01X-78740Y15000D02*
G03X-63740Y0I15000J0D01*
G01X-78740Y15000D02*
Y319646D01*
G01X-63740Y334646D02*
G03X-78740Y319646I0J-15000D01*
G01Y908315D02*
G03X-63740Y893315I15000J0D01*
G01X-78740Y908315D02*
Y1304286D01*
G01X-63740Y1319286D02*
G03X-78740Y1304286I0J-15000D01*
G01Y1892953D02*
G03X-63740Y1877953I15000J0D01*
G01X-78740Y1892953D02*
Y1977126D01*
G01X-63740Y1992126D02*
G03X-78740Y1977126I0J-15000D01*
G01X-7874Y0D02*
X-63740D01*
G01X-7874Y334646D02*
X-63740D01*
G01X-7874Y893315D02*
X-63740D01*
G01X-7874Y1319286D02*
X-63740D01*
G01X-7874Y1877953D02*
X-63740D01*
G01X-7874Y1992126D02*
X-63740D01*
G01X-7874Y17253D02*
Y0D01*
G01X0Y17214D02*
G03X-7874I-3937J0D01*
G01Y41772D02*
Y167110D01*
G01Y41772D02*
G03X0I3937J0D01*
G01Y167110D02*
G03X-7874I-3937J0D01*
G01Y191667D02*
Y308383D01*
G01Y191667D02*
G03X0I3937J0D01*
G01Y308383D02*
G03X-7874I-3937J0D01*
G01Y331986D02*
Y334646D01*
G01Y332003D02*
G03X0I3937J0D01*
G01X-7874Y905988D02*
Y893315D01*
G01X0Y905988D02*
G03X-7874I-3937J0D01*
G01Y1106301D02*
Y933234D01*
G01D02*
G03X0I3937J0D01*
G01Y1106301D02*
G03X-7874I-3937J0D01*
G01Y1280567D02*
Y1129921D01*
G01D02*
G03X0I3937J0D01*
G01Y1280567D02*
G03X-7874I-3937J0D01*
G01Y1309889D02*
Y1319286D01*
G01Y1309889D02*
G03X0I3937J0D01*
G01X-7874Y1889223D02*
Y1877953D01*
G01X0Y1889223D02*
G03X-7874I-3937J0D01*
G01X0D02*
G03X-7874I-3937J0D01*
G01Y1912843D02*
Y1962927D01*
G01Y1912843D02*
G03X0I3937J0D01*
G01Y1962927D02*
G03X-7874I-3937J0D01*
G01X0D02*
G03X-7874I-3937J0D01*
G01Y1986547D02*
Y1992126D01*
G01Y1986547D02*
G03X0I3937J0D01*
G01X3937Y0D02*
X1029528D01*
G01X0Y3937D02*
G03X3937Y0I3937J0D01*
G01X0Y409646D02*
Y3937D01*
G01X3937Y413583D02*
X0Y409646D01*
G01X19882Y413583D02*
X3937D01*
G01Y421063D02*
X19882D01*
G01X0Y425000D02*
X3937Y421063D01*
G01X0Y819094D02*
Y425000D01*
G01X3937Y823031D02*
X0Y819094D01*
G01X19882Y823031D02*
X3937D01*
G01Y830512D02*
X19882D01*
G01X0Y834449D02*
X3937Y830512D01*
G01X0Y1393898D02*
Y834449D01*
G01X3937Y1397835D02*
X0Y1393898D01*
G01X19882Y1397835D02*
X3937D01*
G01Y1405315D02*
X19882D01*
G01X0Y1409252D02*
X3937Y1405315D01*
G01X0Y1803346D02*
Y1409252D01*
G01X3937Y1807283D02*
X0Y1803346D01*
G01X19882Y1807283D02*
X3937D01*
G01Y1814764D02*
X19882D01*
G01X0Y1818701D02*
X3937Y1814764D01*
G01X0Y1988189D02*
Y1818701D01*
G01X3937Y1992126D02*
G03X0Y1988189I0J-3937D01*
G01X1029528Y1992126D02*
X3937D01*
G01X19882Y413583D02*
G03Y421063I0J3740D01*
G01Y823031D02*
G03Y830512I0J3741D01*
G01Y1397835D02*
G03Y1405315I0J3740D01*
G01Y1807283D02*
G03Y1814764I0J3740D01*
G01X989744Y1616083D02*
X1015354D01*
G01X989744D02*
G03Y1611870I0J-2107D01*
G01X1015354D02*
X989744D01*
G01X1033465Y3937D02*
Y1424882D01*
G01X1029528Y0D02*
G03X1033465Y3937I0J3937D01*
G01X1041338Y24677D02*
G03X1033464I-3937J0D01*
G01X1041338D02*
G03X1033464I-3937J0D01*
G01Y48297D02*
G03X1041338I3937J0D01*
G01Y217343D02*
G03X1033464I-3937J0D01*
G01X1041338D02*
G03X1033464I-3937J0D01*
G01Y240964D02*
G03X1041338I3937J0D01*
G01X1033464D02*
G03X1041338I3937J0D01*
G01Y445039D02*
G03X1033464I-3937J0D01*
G01X1041338D02*
G03X1033464I-3937J0D01*
G01Y468659D02*
G03X1041338I3937J0D01*
G01X1033464D02*
G03X1041338I3937J0D01*
G01Y697473D02*
G03X1033464I-3937J0D01*
G01X1041338D02*
G03X1033464I-3937J0D01*
G01Y721093D02*
G03X1041338I3937J0D01*
G01X1033464D02*
G03X1041338I3937J0D01*
G01Y996852D02*
G03X1033464I-3937J0D01*
G01X1041338D02*
G03X1033464I-3937J0D01*
G01Y1020472D02*
G03X1041338I3937J0D01*
G01X1033464D02*
G03X1041338I3937J0D01*
G01Y1344060D02*
G03X1033464I-3937J0D01*
G01X1041338D02*
G03X1033464I-3937J0D01*
G01Y1367680D02*
G03X1041338I3937J0D01*
G01X1033464D02*
G03X1041338I3937J0D01*
G01X1033465Y1424882D02*
X1029528Y1428819D01*
G01X1019291Y1433740D02*
Y1607933D01*
G01Y1433740D02*
G03X1024213Y1428819I4921J0D01*
G01X1029528D02*
X1024213D01*
G01X1015354Y1616083D02*
X1019291Y1620020D01*
G01Y1607933D02*
X1015354Y1611870D01*
G01X1019291Y1620020D02*
Y1676496D01*
G01X1029528Y1681417D02*
X1033465Y1685354D01*
G01X1024213Y1681417D02*
G03X1019291Y1676496I-1J-4921D01*
G01X1033465Y1685354D02*
Y1988189D01*
G01X1024213Y1681417D02*
X1029528D01*
G01X1041338Y1739719D02*
G03X1033464I-3937J0D01*
G01X1041338D02*
G03X1033464I-3937J0D01*
G01Y1763339D02*
G03X1041338I3937J0D01*
G01X1033464D02*
G03X1041338I3937J0D01*
G01Y1959242D02*
G03X1033464I-3937J0D01*
G01X1041338D02*
G03X1033464I-3937J0D01*
G01X1033465Y1988189D02*
G03X1029528Y1992126I-3937J0D01*
G01X1033464Y1982862D02*
G03X1041338I3937J0D01*
G01Y24677D02*
Y0D01*
G01D02*
X1097205D01*
G01X1041338Y217343D02*
Y48297D01*
G01Y445039D02*
Y240964D01*
G01Y697473D02*
Y468601D01*
G01Y996852D02*
Y721093D01*
G01Y1344060D02*
Y1020472D01*
G01Y1367680D02*
Y1393701D01*
G01D02*
X1097205D01*
G01X1041338Y1733129D02*
Y1716536D01*
G01X1065043D02*
X1041338D01*
G01Y1739719D02*
Y1731536D01*
G01Y1959242D02*
Y1763310D01*
G01Y1992126D02*
X1097205D01*
G01X1041338Y1982862D02*
Y1992126D01*
G01X1056338Y1716536D02*
X1097205D01*
G01Y0D02*
G03X1112205Y15000I0J15000D01*
G01Y1378701D02*
G03X1097205Y1393701I-15000J0D01*
G01Y1716536D02*
G03X1112205Y1731536I0J15000D01*
G01Y1977126D02*
G03X1097205Y1992126I-15000J0D01*
G01X1112205Y648419D02*
Y15000D01*
G01Y656293D02*
G03Y648419I0J-3937D01*
G01Y1378701D02*
Y656293D01*
G01Y1977126D02*
Y1731536D01*
G54D15*
G01X-87137Y-139897D02*
Y-107897D01*
G01X-75137Y-123897D02*
G02I-12000J0D01*
G01X-80287D02*
G02I-6850J0D01*
G01X-71137D02*
X-103137D01*
G01X-71137Y-139897D02*
Y-219897D01*
G01D02*
X1129963D01*
G01X-71137Y-175397D02*
X1129963D01*
G01X-71137Y-139897D02*
X1129963D01*
G01X342463D02*
Y-219897D01*
G01X479963Y-139897D02*
Y-219897D01*
G01X594963Y-139897D02*
Y-219897D01*
G01X762463Y-139897D02*
Y-219897D01*
G01X932463Y-139897D02*
Y-219897D01*
G01X1129963Y-139897D02*
Y-219897D01*
G01X1157963Y-123897D02*
G02I-12000J0D01*
G01X1152813D02*
G02I-6850J0D01*
G01X1161963D02*
X1129963D01*
G01X1145963Y-139897D02*
Y-107897D01*
G54D16*
G01X-53190Y-209897D02*
Y-192397D01*
G01X-44894D02*
X-53190Y-203189D01*
G01X-43584Y-209897D02*
X-49479Y-198231D01*
G01X-35909Y-209897D02*
Y-192397D01*
X-25865Y-209897D01*
Y-192397D01*
G01X-13387Y-209897D02*
X-15134Y-209605D01*
X-16662Y-208439D01*
X-17972Y-206689D01*
X-18846Y-204647D01*
X-19282Y-202314D01*
Y-199980D01*
X-18846Y-197647D01*
X-17972Y-195605D01*
X-16662Y-193856D01*
X-15134Y-192689D01*
X-13387Y-192397D01*
X-11641Y-192689D01*
X-10112Y-193856D01*
X-8802Y-195605D01*
X-7928Y-197647D01*
X-7492Y-199980D01*
Y-202314D01*
X-7928Y-204647D01*
X-8802Y-206689D01*
X-10112Y-208439D01*
X-11641Y-209605D01*
X-13387Y-209897D01*
G01X-472D02*
X8698Y-192397D01*
G01X-472D02*
X8698Y-209897D01*
G01X34310D02*
Y-192397D01*
X38676D01*
X40423Y-193272D01*
X41733Y-194439D01*
X42825Y-196188D01*
X43698Y-198231D01*
X43916Y-201147D01*
X43698Y-204064D01*
X42825Y-206106D01*
X41733Y-207856D01*
X40423Y-209022D01*
X38676Y-209897D01*
X34310D01*
G01X52246D02*
Y-192397D01*
X57705D01*
X59451Y-193272D01*
X60543Y-194439D01*
X60980Y-196772D01*
X60543Y-199106D01*
X59233Y-200564D01*
X57705Y-201439D01*
X52246D01*
G01X57705D02*
X60980Y-209897D01*
G01X71493Y-192397D02*
X76733D01*
G01X74113D02*
Y-209897D01*
G01X71493D02*
X76733D01*
G01X86154Y-192397D02*
X91613Y-209897D01*
X97072Y-192397D01*
G01X113480Y-209897D02*
X104746D01*
Y-192397D01*
X113480D01*
G01X109986Y-200855D02*
X104746D01*
G01X139746Y-209897D02*
Y-192397D01*
X144986D01*
X146733Y-193272D01*
X148043Y-195314D01*
X148480Y-197647D01*
X148043Y-199980D01*
X146951Y-201730D01*
X144986Y-202606D01*
X139746D01*
G01X157246Y-192397D02*
Y-209897D01*
X165980D01*
G01X173654D02*
X179113Y-192397D01*
X184572Y-209897D01*
G01X182606Y-203772D02*
X175619D01*
G01X191591Y-209897D02*
Y-192397D01*
X201635Y-209897D01*
Y-192397D01*
G01X218480Y-209897D02*
X209746D01*
Y-192397D01*
X218480D01*
G01X214986Y-200855D02*
X209746D01*
G01X250859Y-200564D02*
X251733Y-199689D01*
X252388Y-198231D01*
X252825Y-196188D01*
X252388Y-194439D01*
X251515Y-193272D01*
X249986Y-192397D01*
X244091D01*
Y-209897D01*
X251296D01*
X252825Y-208731D01*
X253698Y-206980D01*
X254135Y-204939D01*
X253698Y-202897D01*
X252388Y-201147D01*
X250859Y-200564D01*
X244091D01*
G01X266613Y-209897D02*
X264866Y-209605D01*
X263338Y-208439D01*
X262028Y-206689D01*
X261154Y-204647D01*
X260718Y-202314D01*
Y-199980D01*
X261154Y-197647D01*
X262028Y-195605D01*
X263338Y-193856D01*
X264866Y-192689D01*
X266613Y-192397D01*
X268359Y-192689D01*
X269888Y-193856D01*
X271198Y-195605D01*
X272072Y-197647D01*
X272508Y-199980D01*
Y-202314D01*
X272072Y-204647D01*
X271198Y-206689D01*
X269888Y-208439D01*
X268359Y-209605D01*
X266613Y-209897D01*
G01X278654D02*
X284113Y-192397D01*
X289572Y-209897D01*
G01X287606Y-203772D02*
X280619D01*
G01X297246Y-209897D02*
Y-192397D01*
X302705D01*
X304451Y-193272D01*
X305543Y-194439D01*
X305980Y-196772D01*
X305543Y-199106D01*
X304233Y-200564D01*
X302705Y-201439D01*
X297246D01*
G01X302705D02*
X305980Y-209897D01*
G01X314310D02*
Y-192397D01*
X318676D01*
X320423Y-193272D01*
X321733Y-194439D01*
X322825Y-196188D01*
X323698Y-198231D01*
X323916Y-201147D01*
X323698Y-204064D01*
X322825Y-206106D01*
X321733Y-207856D01*
X320423Y-209022D01*
X318676Y-209897D01*
X314310D01*
G01X94686Y-164897D02*
Y-147397D01*
X100363Y-161980D01*
X106040Y-147397D01*
Y-164897D01*
G01X117863D02*
X116553Y-164605D01*
X115243Y-163439D01*
X114369Y-161397D01*
X113933Y-159064D01*
X114369Y-156730D01*
X115243Y-154689D01*
X116553Y-153522D01*
X117863Y-153231D01*
X119173Y-153522D01*
X120483Y-154689D01*
X121356Y-156730D01*
X121575Y-159064D01*
X121356Y-161397D01*
X120483Y-163439D01*
X119173Y-164605D01*
X117863Y-164897D01*
G01X139293Y-147397D02*
Y-164897D01*
G01Y-162273D02*
X138420Y-163731D01*
X137109Y-164605D01*
X135581Y-164897D01*
X133835Y-164314D01*
X132525Y-162856D01*
X131651Y-161106D01*
X131433Y-159064D01*
X131651Y-157022D01*
X132525Y-155272D01*
X133835Y-153814D01*
X135581Y-153231D01*
X137109Y-153522D01*
X138201Y-154106D01*
X139293Y-155272D01*
G01X149588Y-157022D02*
X156575D01*
X155920Y-154980D01*
X154828Y-153814D01*
X153300Y-153231D01*
X151771Y-153522D01*
X150461Y-154397D01*
X149588Y-156439D01*
X149151Y-158189D01*
Y-159939D01*
X149588Y-161689D01*
X150680Y-163439D01*
X151990Y-164605D01*
X153518Y-164897D01*
X155046Y-164314D01*
X156575Y-162564D01*
G01X170363Y-164897D02*
Y-147397D01*
G01X376163Y-209897D02*
Y-192397D01*
X373543Y-195897D01*
G01Y-209897D02*
X378783D01*
G01X389515Y-195314D02*
X390825Y-193564D01*
X392353Y-192689D01*
X394100Y-192397D01*
X396283Y-192980D01*
X397811Y-194439D01*
X398248Y-196188D01*
X398030Y-197939D01*
X397156Y-199397D01*
X392790Y-202314D01*
X390825Y-204355D01*
X389515Y-207273D01*
X389078Y-209897D01*
X398248D01*
G01X413783D02*
Y-192397D01*
X405704Y-204939D01*
X416622D01*
G01X423860Y-206397D02*
X425169Y-208439D01*
X426916Y-209605D01*
X428881Y-209897D01*
X430628Y-209605D01*
X432375Y-208147D01*
X433466Y-206397D01*
X433685Y-204647D01*
X433248Y-202606D01*
X431720Y-201147D01*
X430191Y-200564D01*
X428226D01*
G01X430191D02*
X431501Y-199689D01*
X432593Y-198231D01*
X433030Y-196481D01*
X432593Y-194730D01*
X431501Y-193272D01*
X429536Y-192397D01*
X427571Y-192689D01*
X425606Y-193856D01*
G01X442015Y-195314D02*
X443325Y-193564D01*
X444853Y-192689D01*
X446600Y-192397D01*
X448783Y-192980D01*
X450311Y-194439D01*
X450748Y-196188D01*
X450530Y-197939D01*
X449656Y-199397D01*
X445290Y-202314D01*
X443325Y-204355D01*
X442015Y-207273D01*
X441578Y-209897D01*
X450748D01*
G01X363046Y-164897D02*
Y-147397D01*
X368286D01*
X370033Y-148272D01*
X371343Y-150314D01*
X371780Y-152647D01*
X371343Y-154980D01*
X370251Y-156730D01*
X368286Y-157606D01*
X363046D01*
G01X389716Y-148856D02*
X388406Y-147980D01*
X386878Y-147397D01*
X385131D01*
X383166Y-148272D01*
X381638Y-149730D01*
X380546Y-151481D01*
X379673Y-154397D01*
X379454Y-157022D01*
X379891Y-159647D01*
X380546Y-161397D01*
X381856Y-163147D01*
X383385Y-164314D01*
X384913Y-164897D01*
X386441D01*
X387970Y-164314D01*
X389280Y-163439D01*
X390372Y-162273D01*
G01X404159Y-155564D02*
X405033Y-154689D01*
X405688Y-153231D01*
X406125Y-151188D01*
X405688Y-149439D01*
X404815Y-148272D01*
X403286Y-147397D01*
X397391D01*
Y-164897D01*
X404596D01*
X406125Y-163731D01*
X406998Y-161980D01*
X407435Y-159939D01*
X406998Y-157897D01*
X405688Y-156147D01*
X404159Y-155564D01*
X397391D01*
G01X413363Y-170730D02*
X426463D01*
G01X432391Y-164897D02*
Y-147397D01*
X442435Y-164897D01*
Y-147397D01*
G01X454913Y-164897D02*
X453166Y-164605D01*
X451638Y-163439D01*
X450328Y-161689D01*
X449454Y-159647D01*
X449018Y-157314D01*
Y-154980D01*
X449454Y-152647D01*
X450328Y-150605D01*
X451638Y-148856D01*
X453166Y-147689D01*
X454913Y-147397D01*
X456659Y-147689D01*
X458188Y-148856D01*
X459498Y-150605D01*
X460372Y-152647D01*
X460808Y-154980D01*
Y-157314D01*
X460372Y-159647D01*
X459498Y-161689D01*
X458188Y-163439D01*
X456659Y-164605D01*
X454913Y-164897D01*
G01X505754Y-147397D02*
X511213Y-164897D01*
X516672Y-147397D01*
G01X533080Y-164897D02*
X524346D01*
Y-147397D01*
X533080D01*
G01X529586Y-155855D02*
X524346D01*
G01X541846Y-164897D02*
Y-147397D01*
X547305D01*
X549051Y-148272D01*
X550143Y-149439D01*
X550580Y-151772D01*
X550143Y-154106D01*
X548833Y-155564D01*
X547305Y-156439D01*
X541846D01*
G01X547305D02*
X550580Y-164897D01*
G01X563713Y-165480D02*
X563276Y-165189D01*
Y-164605D01*
X563713Y-164314D01*
X564150Y-164605D01*
Y-165189D01*
X563713Y-165480D01*
G01X537463Y-209897D02*
Y-192397D01*
X534843Y-195897D01*
G01Y-209897D02*
X540083D01*
G01X630546Y-147397D02*
Y-164897D01*
X639280D01*
G01X656343D02*
Y-153231D01*
G01Y-155272D02*
X655470Y-154106D01*
X654159Y-153522D01*
X652631Y-153231D01*
X651103Y-153814D01*
X649793Y-154980D01*
X648919Y-156730D01*
X648483Y-159064D01*
X648919Y-161397D01*
X649793Y-163147D01*
X651103Y-164314D01*
X652631Y-164897D01*
X654159Y-164605D01*
X655470Y-163731D01*
X656343Y-162564D01*
G01X665328Y-170147D02*
X666638Y-170730D01*
X668385Y-170147D01*
X669476Y-168981D01*
X670350Y-167522D01*
X671659Y-162856D01*
X674498Y-153231D01*
G01X667511D02*
X671659Y-162856D01*
G01X684138Y-157022D02*
X691125D01*
X690470Y-154980D01*
X689378Y-153814D01*
X687850Y-153231D01*
X686321Y-153522D01*
X685011Y-154397D01*
X684138Y-156439D01*
X683701Y-158189D01*
Y-159939D01*
X684138Y-161689D01*
X685230Y-163439D01*
X686540Y-164605D01*
X688068Y-164897D01*
X689596Y-164314D01*
X691125Y-162564D01*
G01X701856Y-164897D02*
Y-153231D01*
G01Y-155564D02*
X702948Y-154397D01*
X704040Y-153522D01*
X705568Y-153231D01*
X706659Y-153522D01*
X707970Y-154397D01*
G01X719138Y-162856D02*
X720230Y-164022D01*
X721758Y-164897D01*
X723068D01*
X724378Y-164314D01*
X725251Y-163439D01*
X725688Y-162273D01*
X725470Y-160522D01*
X724596Y-159647D01*
X720666Y-157897D01*
X719793Y-155855D01*
X720230Y-154397D01*
X721103Y-153522D01*
X722413Y-153231D01*
X723723Y-153522D01*
X725033Y-154397D01*
G01X703167Y-200564D02*
X702293Y-199689D01*
X701638Y-198231D01*
X701201Y-196188D01*
X701638Y-194439D01*
X702511Y-193272D01*
X704040Y-192397D01*
X709935D01*
Y-209897D01*
X702730D01*
X701201Y-208731D01*
X700328Y-206980D01*
X699891Y-204939D01*
X700328Y-202897D01*
X701638Y-201147D01*
X703167Y-200564D01*
X709935D01*
G01X691998Y-207564D02*
X690251Y-209022D01*
X688286Y-209897D01*
X686540D01*
X684793Y-209022D01*
X683483Y-207564D01*
X682828Y-205522D01*
X683265Y-203481D01*
X684356Y-201730D01*
X686321Y-200564D01*
X688941Y-199980D01*
X690470Y-198814D01*
X691125Y-196772D01*
X690688Y-194730D01*
X689596Y-193272D01*
X688068Y-192397D01*
X686540D01*
X685011Y-192980D01*
X683701Y-194439D01*
G01X675590Y-209897D02*
Y-192397D01*
X669913Y-206980D01*
X664236Y-192397D01*
Y-209897D01*
G01X657216D02*
Y-192397D01*
X652850D01*
X651103Y-193272D01*
X649793Y-194439D01*
X648701Y-196188D01*
X647828Y-198231D01*
X647610Y-201147D01*
X647828Y-204064D01*
X648701Y-206106D01*
X649793Y-207856D01*
X651103Y-209022D01*
X652850Y-209897D01*
X657216D01*
G01X781410Y-164897D02*
Y-147397D01*
X785776D01*
X787523Y-148272D01*
X788833Y-149439D01*
X789925Y-151188D01*
X790798Y-153231D01*
X791016Y-156147D01*
X790798Y-159064D01*
X789925Y-161106D01*
X788833Y-162856D01*
X787523Y-164022D01*
X785776Y-164897D01*
X781410D01*
G01X800438Y-157022D02*
X807425D01*
X806770Y-154980D01*
X805678Y-153814D01*
X804150Y-153231D01*
X802621Y-153522D01*
X801311Y-154397D01*
X800438Y-156439D01*
X800001Y-158189D01*
Y-159939D01*
X800438Y-161689D01*
X801530Y-163439D01*
X802840Y-164605D01*
X804368Y-164897D01*
X805896Y-164314D01*
X807425Y-162564D01*
G01X817938Y-162856D02*
X819030Y-164022D01*
X820558Y-164897D01*
X821868D01*
X823178Y-164314D01*
X824051Y-163439D01*
X824488Y-162273D01*
X824270Y-160522D01*
X823396Y-159647D01*
X819466Y-157897D01*
X818593Y-155855D01*
X819030Y-154397D01*
X819903Y-153522D01*
X821213Y-153231D01*
X822523Y-153522D01*
X823833Y-154397D01*
G01X838713Y-153231D02*
Y-164897D01*
G01Y-148564D02*
X838276Y-148272D01*
Y-147689D01*
X838713Y-147397D01*
X839150Y-147689D01*
Y-148272D01*
X838713Y-148564D01*
G01X853156Y-169272D02*
X854685Y-170439D01*
X856431Y-170730D01*
X857959Y-170439D01*
X859270Y-168981D01*
X860143Y-166939D01*
Y-153231D01*
G01Y-155564D02*
X859270Y-154397D01*
X857959Y-153522D01*
X856431Y-153231D01*
X854685Y-153814D01*
X853593Y-154980D01*
X852719Y-157022D01*
X852283Y-159064D01*
X852501Y-160814D01*
X853375Y-162856D01*
X854685Y-164314D01*
X856431Y-164897D01*
X857741Y-164605D01*
X859270Y-163439D01*
X860143Y-162273D01*
G01X870001Y-164897D02*
Y-153231D01*
G01Y-156147D02*
X870875Y-154689D01*
X872185Y-153522D01*
X873931Y-153231D01*
X875459Y-153522D01*
X876770Y-154689D01*
X877425Y-156730D01*
Y-164897D01*
G01X887938Y-157022D02*
X894925D01*
X894270Y-154980D01*
X893178Y-153814D01*
X891650Y-153231D01*
X890121Y-153522D01*
X888811Y-154397D01*
X887938Y-156439D01*
X887501Y-158189D01*
Y-159939D01*
X887938Y-161689D01*
X889030Y-163439D01*
X890340Y-164605D01*
X891868Y-164897D01*
X893396Y-164314D01*
X894925Y-162564D01*
G01X905656Y-164897D02*
Y-153231D01*
G01Y-155564D02*
X906748Y-154397D01*
X907840Y-153522D01*
X909368Y-153231D01*
X910459Y-153522D01*
X911770Y-154397D01*
G01X825596Y-209897D02*
Y-192397D01*
X831055D01*
X832801Y-193272D01*
X833893Y-194439D01*
X834330Y-196772D01*
X833893Y-199106D01*
X832583Y-200564D01*
X831055Y-201439D01*
X825596D01*
G01X831055D02*
X834330Y-209897D01*
G01X847463D02*
X846153Y-209605D01*
X844843Y-208439D01*
X843969Y-206397D01*
X843533Y-204064D01*
X843969Y-201730D01*
X844843Y-199689D01*
X846153Y-198522D01*
X847463Y-198231D01*
X848773Y-198522D01*
X850083Y-199689D01*
X850956Y-201730D01*
X851175Y-204064D01*
X850956Y-206397D01*
X850083Y-208439D01*
X848773Y-209605D01*
X847463Y-209897D01*
G01X861033D02*
Y-192397D01*
G01Y-201147D02*
X862125Y-199397D01*
X863435Y-198522D01*
X864745Y-198231D01*
X866709Y-198814D01*
X868020Y-199980D01*
X868893Y-202022D01*
Y-204355D01*
X868456Y-206689D01*
X867583Y-208439D01*
X866055Y-209605D01*
X864745Y-209897D01*
X863435Y-209605D01*
X862125Y-208731D01*
X861033Y-207273D01*
G01X952413Y-209897D02*
Y-192397D01*
X949793Y-195897D01*
G01Y-209897D02*
X955033D01*
G01X969913Y-192397D02*
X968166Y-192980D01*
X966856Y-194439D01*
X965983Y-196188D01*
X965328Y-198522D01*
X965110Y-201147D01*
X965328Y-203772D01*
X965983Y-206106D01*
X966856Y-207856D01*
X968166Y-209314D01*
X969913Y-209897D01*
X971659Y-209314D01*
X972970Y-207856D01*
X973843Y-206106D01*
X974498Y-203772D01*
X974716Y-201147D01*
X974498Y-198522D01*
X973843Y-196188D01*
X972970Y-194439D01*
X971659Y-192980D01*
X969913Y-192397D01*
G01X983483Y-210480D02*
X991343Y-192397D01*
G01X1004913Y-209897D02*
Y-192397D01*
X1002293Y-195897D01*
G01Y-209897D02*
X1007533D01*
G01X1018265Y-202606D02*
X1019793Y-200564D01*
X1021103Y-199397D01*
X1022850Y-198814D01*
X1024378Y-199397D01*
X1025470Y-200564D01*
X1026343Y-202314D01*
X1026561Y-204355D01*
X1026343Y-206106D01*
X1025470Y-207856D01*
X1024159Y-209314D01*
X1022631Y-209897D01*
X1020885Y-209314D01*
X1019356Y-207564D01*
X1018483Y-204939D01*
X1018265Y-202022D01*
X1018701Y-198231D01*
X1019356Y-196188D01*
X1020448Y-194147D01*
X1021976Y-192689D01*
X1023505Y-192397D01*
X1025033Y-192980D01*
X1026125Y-194439D01*
G01X1035983Y-210480D02*
X1043843Y-192397D01*
G01X1053265Y-195314D02*
X1054575Y-193564D01*
X1056103Y-192689D01*
X1057850Y-192397D01*
X1060033Y-192980D01*
X1061561Y-194439D01*
X1061998Y-196188D01*
X1061780Y-197939D01*
X1060906Y-199397D01*
X1056540Y-202314D01*
X1054575Y-204355D01*
X1053265Y-207273D01*
X1052828Y-209897D01*
X1061998D01*
G01X1074913Y-192397D02*
X1073166Y-192980D01*
X1071856Y-194439D01*
X1070983Y-196188D01*
X1070328Y-198522D01*
X1070110Y-201147D01*
X1070328Y-203772D01*
X1070983Y-206106D01*
X1071856Y-207856D01*
X1073166Y-209314D01*
X1074913Y-209897D01*
X1076659Y-209314D01*
X1077970Y-207856D01*
X1078843Y-206106D01*
X1079498Y-203772D01*
X1079716Y-201147D01*
X1079498Y-198522D01*
X1078843Y-196188D01*
X1077970Y-194439D01*
X1076659Y-192980D01*
X1074913Y-192397D01*
G01X1092413Y-209897D02*
Y-192397D01*
X1089793Y-195897D01*
G01Y-209897D02*
X1095033D01*
G01X1105765Y-195314D02*
X1107075Y-193564D01*
X1108603Y-192689D01*
X1110350Y-192397D01*
X1112533Y-192980D01*
X1114061Y-194439D01*
X1114498Y-196188D01*
X1114280Y-197939D01*
X1113406Y-199397D01*
X1109040Y-202314D01*
X1107075Y-204355D01*
X1105765Y-207273D01*
X1105328Y-209897D01*
X1114498D01*
G01X1000110Y-164897D02*
Y-147397D01*
X1004476D01*
X1006223Y-148272D01*
X1007533Y-149439D01*
X1008625Y-151188D01*
X1009498Y-153231D01*
X1009716Y-156147D01*
X1009498Y-159064D01*
X1008625Y-161106D01*
X1007533Y-162856D01*
X1006223Y-164022D01*
X1004476Y-164897D01*
X1000110D01*
G01X1026343D02*
Y-153231D01*
G01Y-155272D02*
X1025470Y-154106D01*
X1024159Y-153522D01*
X1022631Y-153231D01*
X1021103Y-153814D01*
X1019793Y-154980D01*
X1018919Y-156730D01*
X1018483Y-159064D01*
X1018919Y-161397D01*
X1019793Y-163147D01*
X1021103Y-164314D01*
X1022631Y-164897D01*
X1024159Y-164605D01*
X1025470Y-163731D01*
X1026343Y-162564D01*
G01X1039913Y-147397D02*
Y-164897D01*
G01X1036856Y-153231D02*
X1042970D01*
G01X1054138Y-157022D02*
X1061125D01*
X1060470Y-154980D01*
X1059378Y-153814D01*
X1057850Y-153231D01*
X1056321Y-153522D01*
X1055011Y-154397D01*
X1054138Y-156439D01*
X1053701Y-158189D01*
Y-159939D01*
X1054138Y-161689D01*
X1055230Y-163439D01*
X1056540Y-164605D01*
X1058068Y-164897D01*
X1059596Y-164314D01*
X1061125Y-162564D01*
M02*
